(kicad_pcb
	(version 20260206)
	(generator "pcbnew")
	(generator_version "10.0")
	(general
		(thickness 1.6)
		(legacy_teardrops no)
	)
	(paper "A4")
	(title_block
		(title "v1-chassis-manager — T6M_CM_d_v01_1031_1645.brd")
		(comment 1 "Open CloudServer (Microsoft) / footprints 2314-2322 of 2512")
	)
	(layers
		(0 "F.Cu" signal "TOP")
		(4 "In1.Cu" signal "GND1")
		(6 "In2.Cu" signal "IN1")
		(8 "In3.Cu" signal "VCC1")
		(10 "In4.Cu" signal "VCC2")
		(12 "In5.Cu" signal "GND2")
		(14 "In6.Cu" signal "IN2")
		(16 "In7.Cu" signal "IN3")
		(18 "In8.Cu" signal "GND3")
		(2 "B.Cu" signal "BOTTOM")
		(9 "F.Adhes" user "F.Adhesive")
		(11 "B.Adhes" user "B.Adhesive")
		(13 "F.Paste" user "Package Geometry/Pastemask Top")
		(15 "B.Paste" user "Package Geometry/Pastemask Bottom")
		(5 "F.SilkS" user "Ref Des/Silkscreen Top")
		(7 "B.SilkS" user "Ref Des/Silkscreen Bottom")
		(1 "F.Mask" user "Board Geometry/Soldermask Top")
		(3 "B.Mask" user "Board Geometry/Soldermask Bottom")
		(17 "Dwgs.User" user "User.Drawings")
		(19 "Cmts.User" user "User.Comments")
		(21 "Eco1.User" user "User.Eco1")
		(23 "Eco2.User" user "User.Eco2")
		(25 "Edge.Cuts" user "Board Geometry/Outline")
		(27 "Margin" user)
		(31 "F.CrtYd" user "Package Geometry/Place Bound Top")
		(29 "B.CrtYd" user "Package Geometry/Place Bound Bottom")
		(35 "F.Fab" user "Ref Des/Assembly Top")
		(33 "B.Fab" user "Ref Des/Assembly Bottom")
	)
	(footprint ""
		(layer "B.Cu")
		(at 154.06116 -176.569624)
		(property "Reference" "R745"
			(at -1.323086 12.476226 0)
			(unlocked yes)
			(layer "B.SilkS")
			(effects
				(font
					(size 0.7874 0.5842)
					(thickness 0.1524)
				)
				(justify left mirror)
			)
		)
		(property "Value" ""
			(at 0 0 0)
			(layer "B.Fab")
			(effects
				(font
					(size 1.27 1.27)
				)
				(justify mirror)
			)
		)
		(duplicate_pad_numbers_are_jumpers no)
		(fp_line
			(start -0.7874 -0.4064)
			(end -0.7874 0.4064)
			(stroke
				(width 0.1524)
				(type default)
			)
			(layer "B.SilkS")
		)
		(fp_line
			(start -0.7874 0.4064)
			(end 0.7874 0.4064)
			(stroke
				(width 0.1524)
				(type default)
			)
			(layer "B.SilkS")
		)
		(fp_line
			(start 0.7874 -0.4064)
			(end -0.7874 -0.4064)
			(stroke
				(width 0.1524)
				(type default)
			)
			(layer "B.SilkS")
		)
		(fp_line
			(start 0.7874 0.4064)
			(end 0.7874 -0.4064)
			(stroke
				(width 0.1524)
				(type default)
			)
			(layer "B.SilkS")
		)
		(fp_poly
			(pts
				(xy 0.508 0.2794) (xy 0.508 0.2286) (xy 0.635 0.2286) (xy 0.635 -0.254) (xy 0.5334 -0.254) (xy 0.5334 -0.2794)
				(xy -0.5334 -0.2794) (xy -0.5334 -0.254) (xy -0.635 -0.254) (xy -0.635 0.254) (xy -0.5334 0.254)
				(xy -0.5334 0.2794)
			)
			(stroke
				(width 0)
				(type default)
			)
			(fill no)
			(layer "B.CrtYd")
		)
		(pad "1" smd rect
			(at -0.40005 0 180)
			(size 0.4572 0.508)
			(layers "B.Cu" "B.Mask" "B.Paste")
			(net "T11_NODE4_EN")
		)
		(pad "2" smd rect
			(at 0.40005 0 180)
			(size 0.4572 0.508)
			(layers "B.Cu" "B.Mask" "B.Paste")
			(net "P5V_NODE1")
		)
	)
	(footprint ""
		(layer "B.Cu")
		(at 175.038004 -116.29771 -90)
		(property "Reference" "C786"
			(at 3.083052 -0.327152 270)
			(unlocked yes)
			(layer "B.SilkS")
			(effects
				(font
					(size 0.7874 0.5842)
					(thickness 0.1524)
				)
				(justify mirror)
			)
		)
		(property "Value" ""
			(at 0 0 90)
			(layer "B.Fab")
			(effects
				(font
					(size 1.27 1.27)
				)
				(justify mirror)
			)
		)
		(duplicate_pad_numbers_are_jumpers no)
		(fp_line
			(start -1.2954 0.5842)
			(end 1.2954 0.5842)
			(stroke
				(width 0.1524)
				(type default)
			)
			(layer "B.SilkS")
		)
		(fp_line
			(start 1.2954 0.5842)
			(end 1.2954 -0.5842)
			(stroke
				(width 0.1524)
				(type default)
			)
			(layer "B.SilkS")
		)
		(fp_line
			(start -1.2954 -0.5842)
			(end -1.2954 0.5842)
			(stroke
				(width 0.1524)
				(type default)
			)
			(layer "B.SilkS")
		)
		(fp_line
			(start 0 -0.5842)
			(end 0 0.5842)
			(stroke
				(width 0.1524)
				(type default)
			)
			(layer "B.SilkS")
		)
		(fp_line
			(start 1.2954 -0.5842)
			(end -1.2954 -0.5842)
			(stroke
				(width 0.1524)
				(type default)
			)
			(layer "B.SilkS")
		)
		(fp_poly
			(pts
				(xy -0.8636 -0.4572) (xy -0.8636 -0.3556) (xy -1.143 -0.3556) (xy -1.143 0.3556) (xy -0.8636 0.3556)
				(xy -0.8636 0.4572) (xy 0.8636 0.4572) (xy 0.8636 0.3556) (xy 1.143 0.3556) (xy 1.143 -0.3556) (xy 0.8636 -0.3556)
				(xy 0.8636 -0.4572)
			)
			(stroke
				(width 0)
				(type default)
			)
			(fill no)
			(layer "B.CrtYd")
		)
		(fp_line
			(start -0.884936 0.504952)
			(end 0.884936 0.504952)
			(stroke
				(width 0.1)
				(type default)
			)
			(layer "B.Fab")
		)
		(fp_line
			(start 0.884936 0.504952)
			(end 0.884936 -0.504952)
			(stroke
				(width 0.1)
				(type default)
			)
			(layer "B.Fab")
		)
		(fp_line
			(start -0.884936 -0.504952)
			(end -0.884936 0.504952)
			(stroke
				(width 0.1)
				(type default)
			)
			(layer "B.Fab")
		)
		(fp_line
			(start 0.884936 -0.504952)
			(end -0.884936 -0.504952)
			(stroke
				(width 0.1)
				(type default)
			)
			(layer "B.Fab")
		)
		(pad "1" smd rect
			(at -0.7366 0)
			(size 0.7112 0.8128)
			(layers "B.Cu" "B.Mask" "B.Paste")
			(net "P3V3_STB_NODE1")
		)
		(pad "2" smd rect
			(at 0.7366 0)
			(size 0.7112 0.8128)
			(layers "B.Cu" "B.Mask" "B.Paste")
			(net "GND")
		)
	)
	(footprint ""
		(layer "B.Cu")
		(at 123.70816 -175.426624)
		(property "Reference" "R726"
			(at -28.598876 31.521146 0)
			(unlocked yes)
			(layer "B.SilkS")
			(effects
				(font
					(size 0.7874 0.5842)
					(thickness 0.1524)
				)
				(justify left mirror)
			)
		)
		(property "Value" ""
			(at 0 0 0)
			(layer "B.Fab")
			(effects
				(font
					(size 1.27 1.27)
				)
				(justify mirror)
			)
		)
		(duplicate_pad_numbers_are_jumpers no)
		(fp_line
			(start -0.7874 -0.4064)
			(end -0.7874 0.4064)
			(stroke
				(width 0.1524)
				(type default)
			)
			(layer "B.SilkS")
		)
		(fp_line
			(start -0.7874 0.4064)
			(end 0.7874 0.4064)
			(stroke
				(width 0.1524)
				(type default)
			)
			(layer "B.SilkS")
		)
		(fp_line
			(start 0.7874 -0.4064)
			(end -0.7874 -0.4064)
			(stroke
				(width 0.1524)
				(type default)
			)
			(layer "B.SilkS")
		)
		(fp_line
			(start 0.7874 0.4064)
			(end 0.7874 -0.4064)
			(stroke
				(width 0.1524)
				(type default)
			)
			(layer "B.SilkS")
		)
		(fp_poly
			(pts
				(xy 0.508 0.2794) (xy 0.508 0.2286) (xy 0.635 0.2286) (xy 0.635 -0.254) (xy 0.5334 -0.254) (xy 0.5334 -0.2794)
				(xy -0.5334 -0.2794) (xy -0.5334 -0.254) (xy -0.635 -0.254) (xy -0.635 0.254) (xy -0.5334 0.254)
				(xy -0.5334 0.2794)
			)
			(stroke
				(width 0)
				(type default)
			)
			(fill no)
			(layer "B.CrtYd")
		)
		(pad "1" smd rect
			(at -0.40005 0 180)
			(size 0.4572 0.508)
			(layers "B.Cu" "B.Mask" "B.Paste")
			(net "T8_NODE3_EN")
		)
		(pad "2" smd rect
			(at 0.40005 0 180)
			(size 0.4572 0.508)
			(layers "B.Cu" "B.Mask" "B.Paste")
			(net "P5V_NODE1")
		)
	)
	(footprint ""
		(layer "B.Cu")
		(at 39.70782 -149.41169 180)
		(property "Reference" "C397"
			(at 10.382504 9.51992 0)
			(unlocked yes)
			(layer "B.SilkS")
			(effects
				(font
					(size 0.7874 0.5842)
					(thickness 0.1524)
				)
				(justify left mirror)
			)
		)
		(property "Value" ""
			(at 0 0 0)
			(layer "B.Fab")
			(effects
				(font
					(size 1.27 1.27)
				)
				(justify mirror)
			)
		)
		(duplicate_pad_numbers_are_jumpers no)
		(fp_line
			(start 0.7874 0.4064)
			(end 0.7874 -0.4064)
			(stroke
				(width 0.1524)
				(type default)
			)
			(layer "B.SilkS")
		)
		(fp_line
			(start 0.7874 -0.4064)
			(end -0.7874 -0.4064)
			(stroke
				(width 0.1524)
				(type default)
			)
			(layer "B.SilkS")
		)
		(fp_line
			(start 0 0.381)
			(end 0 -0.381)
			(stroke
				(width 0.1524)
				(type default)
			)
			(layer "B.SilkS")
		)
		(fp_line
			(start -0.7874 0.4064)
			(end 0.7874 0.4064)
			(stroke
				(width 0.1524)
				(type default)
			)
			(layer "B.SilkS")
		)
		(fp_line
			(start -0.7874 -0.4064)
			(end -0.7874 0.4064)
			(stroke
				(width 0.1524)
				(type default)
			)
			(layer "B.SilkS")
		)
		(fp_poly
			(pts
				(xy 0.5334 0.254) (xy 0.635 0.254) (xy 0.635 0.2286) (xy 0.635 -0.254) (xy 0.5334 -0.254) (xy 0.5334 -0.2794)
				(xy -0.5334 -0.2794) (xy -0.5334 -0.254) (xy -0.635 -0.254) (xy -0.635 0.254) (xy -0.5334 0.254)
				(xy -0.5334 0.2794) (xy 0.508 0.2794) (xy 0.5334 0.2794)
			)
			(stroke
				(width 0)
				(type default)
			)
			(fill no)
			(layer "B.CrtYd")
		)
		(pad "1" smd rect
			(at -0.40005 0)
			(size 0.4572 0.508)
			(layers "B.Cu" "B.Mask" "B.Paste")
			(net "P3V3_NODE1")
		)
		(pad "2" smd rect
			(at 0.40005 0)
			(size 0.4572 0.508)
			(layers "B.Cu" "B.Mask" "B.Paste")
			(net "GND")
		)
	)
	(footprint ""
		(layer "B.Cu")
		(at 75.37069 -124.644404 -90)
		(property "Reference" "C283"
			(at 2.140204 -7.91464 270)
			(unlocked yes)
			(layer "B.SilkS")
			(effects
				(font
					(size 0.7874 0.5842)
					(thickness 0.1524)
				)
				(justify mirror)
			)
		)
		(property "Value" ""
			(at 0 0 90)
			(layer "B.Fab")
			(effects
				(font
					(size 1.27 1.27)
				)
				(justify mirror)
			)
		)
		(duplicate_pad_numbers_are_jumpers no)
		(fp_line
			(start -1.2954 0.5842)
			(end 1.2954 0.5842)
			(stroke
				(width 0.1524)
				(type default)
			)
			(layer "B.SilkS")
		)
		(fp_line
			(start 1.2954 0.5842)
			(end 1.2954 -0.5842)
			(stroke
				(width 0.1524)
				(type default)
			)
			(layer "B.SilkS")
		)
		(fp_line
			(start -1.2954 -0.5842)
			(end -1.2954 0.5842)
			(stroke
				(width 0.1524)
				(type default)
			)
			(layer "B.SilkS")
		)
		(fp_line
			(start 0 -0.5842)
			(end 0 0.5842)
			(stroke
				(width 0.1524)
				(type default)
			)
			(layer "B.SilkS")
		)
		(fp_line
			(start 1.2954 -0.5842)
			(end -1.2954 -0.5842)
			(stroke
				(width 0.1524)
				(type default)
			)
			(layer "B.SilkS")
		)
		(fp_poly
			(pts
				(xy -0.8636 -0.4572) (xy -0.8636 -0.3556) (xy -1.143 -0.3556) (xy -1.143 0.3556) (xy -0.8636 0.3556)
				(xy -0.8636 0.4572) (xy 0.8636 0.4572) (xy 0.8636 0.3556) (xy 1.143 0.3556) (xy 1.143 -0.3556) (xy 0.8636 -0.3556)
				(xy 0.8636 -0.4572)
			)
			(stroke
				(width 0)
				(type default)
			)
			(fill no)
			(layer "B.CrtYd")
		)
		(fp_line
			(start -0.884936 0.504952)
			(end 0.884936 0.504952)
			(stroke
				(width 0.1)
				(type default)
			)
			(layer "B.Fab")
		)
		(fp_line
			(start 0.884936 0.504952)
			(end 0.884936 -0.504952)
			(stroke
				(width 0.1)
				(type default)
			)
			(layer "B.Fab")
		)
		(fp_line
			(start -0.884936 -0.504952)
			(end -0.884936 0.504952)
			(stroke
				(width 0.1)
				(type default)
			)
			(layer "B.Fab")
		)
		(fp_line
			(start 0.884936 -0.504952)
			(end -0.884936 -0.504952)
			(stroke
				(width 0.1)
				(type default)
			)
			(layer "B.Fab")
		)
		(pad "1" smd rect
			(at -0.7366 0)
			(size 0.7112 0.8128)
			(layers "B.Cu" "B.Mask" "B.Paste")
			(net "BMC_NODE1_VCC_1V8_PCIEA")
		)
		(pad "2" smd rect
			(at 0.7366 0)
			(size 0.7112 0.8128)
			(layers "B.Cu" "B.Mask" "B.Paste")
			(net "GND")
		)
	)
	(footprint ""
		(layer "B.Cu")
		(at 65.198498 -96.696784 -90)
		(property "Reference" "R86"
			(at -6.314948 5.033264 270)
			(unlocked yes)
			(layer "B.SilkS")
			(effects
				(font
					(size 0.7874 0.5842)
					(thickness 0.1524)
				)
				(justify left mirror)
			)
		)
		(property "Value" ""
			(at 0 0 90)
			(layer "B.Fab")
			(effects
				(font
					(size 1.27 1.27)
				)
				(justify mirror)
			)
		)
		(duplicate_pad_numbers_are_jumpers no)
		(fp_line
			(start -0.7874 0.4064)
			(end 0.7874 0.4064)
			(stroke
				(width 0.1524)
				(type default)
			)
			(layer "B.SilkS")
		)
		(fp_line
			(start 0.7874 0.4064)
			(end 0.7874 -0.4064)
			(stroke
				(width 0.1524)
				(type default)
			)
			(layer "B.SilkS")
		)
		(fp_line
			(start -0.7874 -0.4064)
			(end -0.7874 0.4064)
			(stroke
				(width 0.1524)
				(type default)
			)
			(layer "B.SilkS")
		)
		(fp_line
			(start 0.7874 -0.4064)
			(end -0.7874 -0.4064)
			(stroke
				(width 0.1524)
				(type default)
			)
			(layer "B.SilkS")
		)
		(fp_poly
			(pts
				(xy 0.508 0.2794) (xy 0.508 0.2286) (xy 0.635 0.2286) (xy 0.635 -0.254) (xy 0.5334 -0.254) (xy 0.5334 -0.2794)
				(xy -0.5334 -0.2794) (xy -0.5334 -0.254) (xy -0.635 -0.254) (xy -0.635 0.254) (xy -0.5334 0.254)
				(xy -0.5334 0.2794)
			)
			(stroke
				(width 0)
				(type default)
			)
			(fill no)
			(layer "B.CrtYd")
		)
		(pad "1" smd rect
			(at -0.40005 0 90)
			(size 0.4572 0.508)
			(layers "B.Cu" "B.Mask" "B.Paste")
			(net "P3V3_NODE1")
		)
		(pad "2" smd rect
			(at 0.40005 0 90)
			(size 0.4572 0.508)
			(layers "B.Cu" "B.Mask" "B.Paste")
			(net "NODE1_BIOS_MB_REV_ID0")
		)
	)
	(footprint ""
		(layer "B.Cu")
		(at 132.750052 -113.975642 90)
		(property "Reference" "C4"
			(at 1.252728 0.302514 270)
			(unlocked yes)
			(layer "B.SilkS")
			(effects
				(font
					(size 0.7874 0.5842)
					(thickness 0.1524)
				)
				(justify left mirror)
			)
		)
		(property "Value" ""
			(at 0 0 90)
			(layer "B.Fab")
			(effects
				(font
					(size 1.27 1.27)
				)
				(justify mirror)
			)
		)
		(duplicate_pad_numbers_are_jumpers no)
		(fp_line
			(start 0.7874 -0.4064)
			(end -0.7874 -0.4064)
			(stroke
				(width 0.1524)
				(type default)
			)
			(layer "B.SilkS")
		)
		(fp_line
			(start -0.7874 -0.4064)
			(end -0.7874 0.4064)
			(stroke
				(width 0.1524)
				(type default)
			)
			(layer "B.SilkS")
		)
		(fp_line
			(start 0 0.381)
			(end 0 -0.381)
			(stroke
				(width 0.1524)
				(type default)
			)
			(layer "B.SilkS")
		)
		(fp_line
			(start 0.7874 0.4064)
			(end 0.7874 -0.4064)
			(stroke
				(width 0.1524)
				(type default)
			)
			(layer "B.SilkS")
		)
		(fp_line
			(start -0.7874 0.4064)
			(end 0.7874 0.4064)
			(stroke
				(width 0.1524)
				(type default)
			)
			(layer "B.SilkS")
		)
		(fp_poly
			(pts
				(xy 0.5334 0.254) (xy 0.635 0.254) (xy 0.635 0.2286) (xy 0.635 -0.254) (xy 0.5334 -0.254) (xy 0.5334 -0.2794)
				(xy -0.5334 -0.2794) (xy -0.5334 -0.254) (xy -0.635 -0.254) (xy -0.635 0.254) (xy -0.5334 0.254)
				(xy -0.5334 0.2794) (xy 0.508 0.2794) (xy 0.5334 0.2794)
			)
			(stroke
				(width 0)
				(type default)
			)
			(fill no)
			(layer "B.CrtYd")
		)
		(pad "1" smd rect
			(at -0.40005 0 270)
			(size 0.4572 0.508)
			(layers "B.Cu" "B.Mask" "B.Paste")
			(net "P3V3_CLK_NODE1")
		)
		(pad "2" smd rect
			(at 0.40005 0 270)
			(size 0.4572 0.508)
			(layers "B.Cu" "B.Mask" "B.Paste")
			(net "GND")
		)
	)
	(footprint ""
		(layer "B.Cu")
		(at 79.23276 -188.126624 -90)
		(property "Reference" "C646"
			(at -4.172712 0.173482 270)
			(unlocked yes)
			(layer "B.SilkS")
			(effects
				(font
					(size 0.7874 0.5842)
					(thickness 0.1524)
				)
				(justify left mirror)
			)
		)
		(property "Value" ""
			(at 0 0 90)
			(layer "B.Fab")
			(effects
				(font
					(size 1.27 1.27)
				)
				(justify mirror)
			)
		)
		(duplicate_pad_numbers_are_jumpers no)
		(fp_line
			(start -0.7874 0.4064)
			(end 0.7874 0.4064)
			(stroke
				(width 0.1524)
				(type default)
			)
			(layer "B.SilkS")
		)
		(fp_line
			(start 0.7874 0.4064)
			(end 0.7874 -0.4064)
			(stroke
				(width 0.1524)
				(type default)
			)
			(layer "B.SilkS")
		)
		(fp_line
			(start 0 0.381)
			(end 0 -0.381)
			(stroke
				(width 0.1524)
				(type default)
			)
			(layer "B.SilkS")
		)
		(fp_line
			(start -0.7874 -0.4064)
			(end -0.7874 0.4064)
			(stroke
				(width 0.1524)
				(type default)
			)
			(layer "B.SilkS")
		)
		(fp_line
			(start 0.7874 -0.4064)
			(end -0.7874 -0.4064)
			(stroke
				(width 0.1524)
				(type default)
			)
			(layer "B.SilkS")
		)
		(fp_poly
			(pts
				(xy 0.5334 0.254) (xy 0.635 0.254) (xy 0.635 0.2286) (xy 0.635 -0.254) (xy 0.5334 -0.254) (xy 0.5334 -0.2794)
				(xy -0.5334 -0.2794) (xy -0.5334 -0.254) (xy -0.635 -0.254) (xy -0.635 0.254) (xy -0.5334 0.254)
				(xy -0.5334 0.2794) (xy 0.508 0.2794) (xy 0.5334 0.2794)
			)
			(stroke
				(width 0)
				(type default)
			)
			(fill no)
			(layer "B.CrtYd")
		)
		(pad "1" smd rect
			(at -0.40005 0 90)
			(size 0.4572 0.508)
			(layers "B.Cu" "B.Mask" "B.Paste")
			(net "T3_NODE1_EN_R")
		)
		(pad "2" smd rect
			(at 0.40005 0 90)
			(size 0.4572 0.508)
			(layers "B.Cu" "B.Mask" "B.Paste")
			(net "GND")
		)
	)
	(footprint ""
		(layer "B.Cu")
		(at 110.44936 -174.537624 180)
		(property "Reference" "R710"
			(at 21.356828 -32.269176 0)
			(unlocked yes)
			(layer "B.SilkS")
			(effects
				(font
					(size 0.7874 0.5842)
					(thickness 0.1524)
				)
				(justify left mirror)
			)
		)
		(property "Value" ""
			(at 0 0 0)
			(layer "B.Fab")
			(effects
				(font
					(size 1.27 1.27)
				)
				(justify mirror)
			)
		)
		(duplicate_pad_numbers_are_jumpers no)
		(fp_line
			(start 0.7874 0.4064)
			(end 0.7874 -0.4064)
			(stroke
				(width 0.1524)
				(type default)
			)
			(layer "B.SilkS")
		)
		(fp_line
			(start 0.7874 -0.4064)
			(end -0.7874 -0.4064)
			(stroke
				(width 0.1524)
				(type default)
			)
			(layer "B.SilkS")
		)
		(fp_line
			(start -0.7874 0.4064)
			(end 0.7874 0.4064)
			(stroke
				(width 0.1524)
				(type default)
			)
			(layer "B.SilkS")
		)
		(fp_line
			(start -0.7874 -0.4064)
			(end -0.7874 0.4064)
			(stroke
				(width 0.1524)
				(type default)
			)
			(layer "B.SilkS")
		)
		(fp_poly
			(pts
				(xy 0.508 0.2794) (xy 0.508 0.2286) (xy 0.635 0.2286) (xy 0.635 -0.254) (xy 0.5334 -0.254) (xy 0.5334 -0.2794)
				(xy -0.5334 -0.2794) (xy -0.5334 -0.254) (xy -0.635 -0.254) (xy -0.635 0.254) (xy -0.5334 0.254)
				(xy -0.5334 0.2794)
			)
			(stroke
				(width 0)
				(type default)
			)
			(fill no)
			(layer "B.CrtYd")
		)
		(pad "1" smd rect
			(at -0.40005 0)
			(size 0.4572 0.508)
			(layers "B.Cu" "B.Mask" "B.Paste")
			(net "T5_NODE1_EN")
		)
		(pad "2" smd rect
			(at 0.40005 0)
			(size 0.4572 0.508)
			(layers "B.Cu" "B.Mask" "B.Paste")
			(net "P5V_NODE1")
		)
	)
)
